# TIMECARD (Time Appliance Project (Time Card)) — schematic netlist excerpt (pin names and nets, part order shuffled) for the footprints in the layout excerpt that follows; sources: Cadence DE-HDL packaged netlist, KiCad conversion of R4006-B0001-02_R01.brd

C186  CAPACITOR  10UF 25V 20%  pkg SMC_0805R_H057  page 30 : \1\ = XP1R8V_VIN ; \2\ = SG
C264  CAPACITOR  18PF 25V 5%  pkg SMC_0201R  page 29 : \1\ = XP1R0V_COMP ; \2\ = XP1R0V_AGND

(kicad_pcb
	(version 20260206)
	(generator "pcbnew")
	(generator_version "10.0")
	(general
		(thickness 1.6)
		(legacy_teardrops no)
	)
	(paper "A4")
	(title_block
		(title "timecard-production-celestica-r4006 — R4006-B0001-02_R01.brd")
		(comment 1 "Time Appliance Project (Time Card) / footprints 202-203 of 1113")
	)
	(layers
		(0 "F.Cu" signal "TOP")
		(4 "In1.Cu" signal "L02_GND1")
		(6 "In2.Cu" signal "L03_SIG1")
		(8 "In3.Cu" signal "L04_GND2")
		(10 "In4.Cu" signal "L05_VCC1")
		(12 "In5.Cu" signal "L06_VCC2")
		(14 "In6.Cu" signal "L07_GND3")
		(16 "In7.Cu" signal "L08_SIG2")
		(18 "In8.Cu" signal "L09_GND4")
		(2 "B.Cu" signal "BOTTOM")
		(9 "F.Adhes" user "F.Adhesive")
		(11 "B.Adhes" user "B.Adhesive")
		(13 "F.Paste" user "Package Geometry/Pastemask Top")
		(15 "B.Paste" user "Package Geometry/Pastemask Bottom")
		(5 "F.SilkS" user "Ref Des/Silkscreen Top")
		(7 "B.SilkS" user "Ref Des/Silkscreen Bottom")
		(1 "F.Mask" user "Board Geometry/Soldermask Top")
		(3 "B.Mask" user "Board Geometry/Soldermask Bottom")
		(17 "Dwgs.User" user "User.Drawings")
		(19 "Cmts.User" user "User.Comments")
		(21 "Eco1.User" user "User.Eco1")
		(23 "Eco2.User" user "User.Eco2")
		(25 "Edge.Cuts" user "Board Geometry/Outline")
		(27 "Margin" user)
		(31 "F.CrtYd" user "Package Geometry/Place Bound Top")
		(29 "B.CrtYd" user "Package Geometry/Place Bound Bottom")
		(35 "F.Fab" user "Ref Des/Assembly Top")
		(33 "B.Fab" user "Ref Des/Assembly Bottom")
	)
	(footprint ""
		(layer "F.Cu")
		(at 128.1938 -64.3636)
		(property "Reference" "C186"
			(at 0.889 5.24637 0)
			(unlocked yes)
			(layer "F.SilkS")
			(effects
				(font
					(size 0.7874 0.5842)
					(thickness 0.1524)
				)
			)
		)
		(property "Value" "VAL*"
			(at 0.0762 3.134106 0)
			(unlocked yes)
			(layer "F.Fab")
			(hide yes)
			(effects
				(font
					(size 0.7874 0.5842)
					(thickness 0.1524)
				)
			)
		)
		(property "Tolerance" "TOL*"
			(at 0.0762 4.048506 0)
			(unlocked yes)
			(layer "Cmts.User")
			(hide yes)
			(effects
				(font
					(size 0.7874 0.5842)
					(thickness 0.1524)
				)
			)
		)
		(property "User Part Number" "PARTNUM*"
			(at 0.1016 5.013706 0)
			(unlocked yes)
			(layer "Cmts.User")
			(hide yes)
			(effects
				(font
					(size 0.7874 0.5842)
					(thickness 0.1524)
				)
			)
		)
		(property "Device Type" "CAPACITOR-G107-0F106-EM,10UF,2A"
			(at 0.0508 2.194306 0)
			(unlocked yes)
			(layer "F.Fab")
			(hide yes)
			(effects
				(font
					(size 0.7874 0.5842)
					(thickness 0.1524)
				)
			)
		)
		(duplicate_pad_numbers_are_jumpers no)
		(fp_line
			(start -1.5748 -0.9398)
			(end -1.5748 0.9398)
			(stroke
				(width 0.1)
				(type default)
			)
			(layer "F.SilkS")
		)
		(fp_line
			(start -1.5748 0.9398)
			(end 1.5748 0.9398)
			(stroke
				(width 0.1)
				(type default)
			)
			(layer "F.SilkS")
		)
		(fp_line
			(start 1.5748 -0.9398)
			(end -1.5748 -0.9398)
			(stroke
				(width 0.1)
				(type default)
			)
			(layer "F.SilkS")
		)
		(fp_line
			(start 1.5748 0.9398)
			(end 1.5748 -0.9398)
			(stroke
				(width 0.1)
				(type default)
			)
			(layer "F.SilkS")
		)
		(fp_rect
			(start 1.5748 -0.9398)
			(end -1.5748 0.9398)
			(stroke
				(width 0)
				(type default)
			)
			(fill no)
			(layer "F.CrtYd")
		)
		(fp_line
			(start -1.016 -0.635)
			(end -1.016 0.635)
			(stroke
				(width 0.1)
				(type default)
			)
			(layer "F.Fab")
		)
		(fp_line
			(start -1.016 0.635)
			(end 1.016 0.635)
			(stroke
				(width 0.1)
				(type default)
			)
			(layer "F.Fab")
		)
		(fp_line
			(start 1.016 -0.635)
			(end -1.016 -0.635)
			(stroke
				(width 0.1)
				(type default)
			)
			(layer "F.Fab")
		)
		(fp_line
			(start 1.016 0.635)
			(end 1.016 -0.635)
			(stroke
				(width 0.1)
				(type default)
			)
			(layer "F.Fab")
		)
		(pad "1" smd rect
			(at -0.8382 0)
			(size 0.9652 1.3716)
			(layers "F.Cu" "F.Mask" "F.Paste")
			(net "XP1R8V_VIN")
		)
		(pad "2" smd rect
			(at 0.8382 0)
			(size 0.9652 1.3716)
			(layers "F.Cu" "F.Mask" "F.Paste")
			(net "SG")
		)
		(zone
			(layer "F.Cu")
			(hatch none 0.5)
			(connect_pads
				(clearance 0)
			)
			(min_thickness 0.25)
			(keepout
				(tracks allowed)
				(vias not_allowed)
				(pads allowed)
				(copperpour not_allowed)
				(footprints allowed)
			)
			(placement
				(enabled no)
				(sheetname "")
			)
			(fill
				(thermal_gap 0.5)
				(thermal_bridge_width 0.5)
				(island_removal_mode 0)
			)
			(polygon
				(pts
					(xy 128.4224 -64.9986) (xy 127.9652 -64.9986) (xy 127.9652 -63.7286) (xy 128.4224 -63.7286)
				)
			)
		)
	)
	(footprint ""
		(layer "F.Cu")
		(at 143.256 -59.436 90)
		(property "Reference" "C264"
			(at 3.175 -1.86563 90)
			(unlocked yes)
			(layer "F.SilkS")
			(effects
				(font
					(size 0.7874 0.5842)
					(thickness 0.1524)
				)
			)
		)
		(property "Value" "VAL*"
			(at 0.193548 2.13614 90)
			(unlocked yes)
			(layer "F.Fab")
			(hide yes)
			(effects
				(font
					(size 0.7874 0.5842)
					(thickness 0.1524)
				)
			)
		)
		(property "Tolerance" "TOL*"
			(at 0.216154 3.1496 90)
			(unlocked yes)
			(layer "Cmts.User")
			(hide yes)
			(effects
				(font
					(size 0.7874 0.5842)
					(thickness 0.1524)
				)
			)
		)
		(property "Device Type" "CAPACITOR-G104-0A180-FJ,18PF,5%"
			(at 0.184404 1.180592 90)
			(unlocked yes)
			(layer "F.Fab")
			(hide yes)
			(effects
				(font
					(size 0.7874 0.5842)
					(thickness 0.1524)
				)
			)
		)
		(property "User Part Number" "PARTNUM*"
			(at 0.216154 4.185666 90)
			(unlocked yes)
			(layer "Cmts.User")
			(hide yes)
			(effects
				(font
					(size 0.7874 0.5842)
					(thickness 0.1524)
				)
			)
		)
		(duplicate_pad_numbers_are_jumpers no)
		(fp_line
			(start 0.671322 -0.4445)
			(end 0.671322 0.4445)
			(stroke
				(width 0.1)
				(type default)
			)
			(layer "F.SilkS")
		)
		(fp_line
			(start -0.671322 -0.4445)
			(end 0.671322 -0.4445)
			(stroke
				(width 0.1)
				(type default)
			)
			(layer "F.SilkS")
		)
		(fp_line
			(start 0.671322 0.4445)
			(end -0.671322 0.4445)
			(stroke
				(width 0.1)
				(type default)
			)
			(layer "F.SilkS")
		)
		(fp_line
			(start -0.671322 0.4445)
			(end -0.671322 -0.4445)
			(stroke
				(width 0.1)
				(type default)
			)
			(layer "F.SilkS")
		)
		(fp_rect
			(start -0.671322 -0.4445)
			(end 0.671322 0.4445)
			(stroke
				(width 0)
				(type default)
			)
			(fill no)
			(layer "F.CrtYd")
		)
		(fp_line
			(start 0.31496 -0.1651)
			(end -0.31496 -0.1651)
			(stroke
				(width 0.1)
				(type default)
			)
			(layer "F.Fab")
		)
		(fp_line
			(start -0.31496 -0.1651)
			(end -0.31496 0.1651)
			(stroke
				(width 0.1)
				(type default)
			)
			(layer "F.Fab")
		)
		(fp_line
			(start 0.31496 0.1651)
			(end 0.31496 -0.1651)
			(stroke
				(width 0.1)
				(type default)
			)
			(layer "F.Fab")
		)
		(fp_line
			(start -0.31496 0.1651)
			(end 0.31496 0.1651)
			(stroke
				(width 0.1)
				(type default)
			)
			(layer "F.Fab")
		)
		(pad "1" smd rect
			(at -0.264922 0 90)
			(size 0.3048 0.381)
			(layers "F.Cu" "F.Mask" "F.Paste")
			(net "XP1R0V_COMP")
		)
		(pad "2" smd rect
			(at 0.264922 0 90)
			(size 0.3048 0.381)
			(layers "F.Cu" "F.Mask" "F.Paste")
			(net "XP1R0V_AGND")
		)
		(zone
			(layer "F.Cu")
			(hatch none 0.5)
			(connect_pads
				(clearance 0)
			)
			(min_thickness 0.25)
			(keepout
				(tracks allowed)
				(vias not_allowed)
				(pads allowed)
				(copperpour not_allowed)
				(footprints allowed)
			)
			(placement
				(enabled no)
				(sheetname "")
			)
			(fill
				(thermal_gap 0.5)
				(thermal_bridge_width 0.5)
				(island_removal_mode 0)
			)
			(polygon
				(pts
					(xy 143.0655 -59.323478) (xy 143.4465 -59.323478) (xy 143.4465 -59.548522) (xy 143.0655 -59.548522)
				)
			)
		)
	)
)
